(kicad_pcb
	(version 20241229)
	(generator "pcbnew")
	(generator_version "9.0")
	(general
		(thickness 1.292)
		(legacy_teardrops no)
	)
	(paper "A4")
	(title_block
		(title "LPDDR5 Testbed")
		(date "2023-12-19")
		(rev "1.0.0")
		(comment 9 "footprints 37-43 of 160")
	)
	(layers
		(0 "F.Cu" signal)
		(4 "In1.Cu" power)
		(6 "In2.Cu" power)
		(8 "In3.Cu" signal)
		(10 "In4.Cu" signal)
		(2 "B.Cu" signal)
		(9 "F.Adhes" user "F.Adhesive")
		(11 "B.Adhes" user "B.Adhesive")
		(13 "F.Paste" user)
		(15 "B.Paste" user)
		(5 "F.SilkS" user "F.Silkscreen")
		(7 "B.SilkS" user "B.Silkscreen")
		(1 "F.Mask" user)
		(3 "B.Mask" user)
		(17 "Dwgs.User" user "User.Drawings")
		(19 "Cmts.User" user "User.Comments")
		(21 "Eco1.User" user "User.Eco1")
		(23 "Eco2.User" user "User.Eco2")
		(25 "Edge.Cuts" user)
		(27 "Margin" user)
		(31 "F.CrtYd" user "F.Courtyard")
		(29 "B.CrtYd" user "B.Courtyard")
		(35 "F.Fab" user)
		(33 "B.Fab" user)
	)
	(footprint "antmicro-footprints:R_0402_1005Metric"
		(layer "F.Cu")
		(at 165.975 65.35 180)
		(descr "Resistor SMD 0402")
		(tags "resistor SMD 0402")
		(property "Reference" "R41"
			(at 4.875 -0.65 0)
			(unlocked yes)
			(layer "F.SilkS")
			(effects
				(font
					(size 0.7 0.7)
					(thickness 0.15)
				)
				(justify right bottom)
			)
		)
		(property "Value" "R_25k5_0402"
			(at -1.011843 1.772047 0)
			(layer "F.Fab")
			(effects
				(font
					(size 0.7 0.7)
					(thickness 0.15)
				)
				(justify right bottom)
			)
		)
		(property "Author" "Antmicro"
			(at 331.95 130.7 0)
			(layer "F.Fab")
			(hide yes)
			(effects
				(font
					(size 1 1)
					(thickness 0.15)
				)
			)
		)
		(property "License" "Apache-2.0"
			(at 331.95 130.7 0)
			(layer "F.Fab")
			(hide yes)
			(effects
				(font
					(size 1 1)
					(thickness 0.15)
				)
			)
		)
		(property "MPN" "CR0402-FX-2552GLF"
			(at 331.95 130.7 0)
			(layer "F.Fab")
			(hide yes)
			(effects
				(font
					(size 1 1)
					(thickness 0.15)
				)
			)
		)
		(property "Manufacturer" "Bourns"
			(at 331.95 130.7 0)
			(layer "F.Fab")
			(hide yes)
			(effects
				(font
					(size 1 1)
					(thickness 0.15)
				)
			)
		)
		(property "Tolerance" "1%"
			(at 331.95 130.7 0)
			(layer "F.Fab")
			(hide yes)
			(effects
				(font
					(size 1 1)
					(thickness 0.15)
				)
			)
		)
		(property "Val" "25k5"
			(at 331.95 130.7 0)
			(layer "F.Fab")
			(hide yes)
			(effects
				(font
					(size 1 1)
					(thickness 0.15)
				)
			)
		)
		(sheetname "Power supply")
		(sheetfile "power_supply.kicad_sch")
		(attr smd)
		(fp_rect
			(start -0.93 -0.47)
			(end 0.93 0.47)
			(stroke
				(width 0.05)
				(type solid)
			)
			(fill no)
			(layer "F.CrtYd")
		)
		(fp_rect
			(start -0.5 -0.25)
			(end 0.5 0.25)
			(stroke
				(width 0.15)
				(type solid)
			)
			(fill no)
			(layer "F.Fab")
		)
		(pad "1" smd roundrect
			(at -0.485 0 180)
			(size 0.59 0.64)
			(layers "F.Cu" "F.Mask" "F.Paste")
			(roundrect_rratio 0.25)
			(net 41 "/Power supply/PWRGD")
			(pintype "passive")
		)
		(pad "2" smd roundrect
			(at 0.485 0 180)
			(size 0.59 0.64)
			(layers "F.Cu" "F.Mask" "F.Paste")
			(roundrect_rratio 0.25)
			(net 1 "+1V1")
			(pintype "passive")
		)
	)
	(footprint "antmicro-footprints:R_0603_1608Metric"
		(layer "F.Cu")
		(at 102.85 61.075)
		(descr "Resistor SMD 0603")
		(tags "resistor SMD 0603")
		(property "Reference" "R43"
			(at -1.25 1.225 90)
			(unlocked yes)
			(layer "F.SilkS")
			(effects
				(font
					(size 0.7 0.7)
					(thickness 0.15)
				)
				(justify left bottom)
			)
		)
		(property "Value" "R_0R_22.4A_0603"
			(at 0 1.6 0)
			(layer "F.Fab")
			(effects
				(font
					(size 0.7 0.7)
					(thickness 0.15)
				)
				(justify left bottom)
			)
		)
		(property "Author" "Antmicro"
			(at 0 0 0)
			(layer "F.Fab")
			(hide yes)
			(effects
				(font
					(size 1 1)
					(thickness 0.15)
				)
			)
		)
		(property "License" "Apache-2.0"
			(at 0 0 0)
			(layer "F.Fab")
			(hide yes)
			(effects
				(font
					(size 1 1)
					(thickness 0.15)
				)
			)
		)
		(property "MPN" "PMR03EZPJ000"
			(at 0 0 0)
			(layer "F.Fab")
			(hide yes)
			(effects
				(font
					(size 1 1)
					(thickness 0.15)
				)
			)
		)
		(property "Manufacturer" "ROHM Semiconductor"
			(at 0 0 0)
			(layer "F.Fab")
			(hide yes)
			(effects
				(font
					(size 1 1)
					(thickness 0.15)
				)
			)
		)
		(property "Max. Curr." "22.4A"
			(at 0 0 0)
			(layer "F.Fab")
			(hide yes)
			(effects
				(font
					(size 1 1)
					(thickness 0.15)
				)
			)
		)
		(property "Tolerance" "template_tolerance"
			(at 0 0 0)
			(layer "F.Fab")
			(hide yes)
			(effects
				(font
					(size 1 1)
					(thickness 0.15)
				)
			)
		)
		(property "Val" "0R"
			(at 0 0 0)
			(layer "F.Fab")
			(hide yes)
			(effects
				(font
					(size 1 1)
					(thickness 0.15)
				)
			)
		)
		(sheetname "Power supply")
		(sheetfile "power_supply.kicad_sch")
		(attr smd)
		(fp_line
			(start -0.3 -0.3)
			(end 0.3 -0.3)
			(stroke
				(width 0.15)
				(type solid)
			)
			(layer "F.SilkS")
		)
		(fp_line
			(start -0.3 0.3)
			(end 0.3 0.3)
			(stroke
				(width 0.15)
				(type solid)
			)
			(layer "F.SilkS")
		)
		(fp_rect
			(start -1.25 -0.7)
			(end 1.25 0.7)
			(stroke
				(width 0.05)
				(type solid)
			)
			(fill no)
			(layer "F.CrtYd")
		)
		(fp_rect
			(start -0.8 -0.4)
			(end 0.8 0.4)
			(stroke
				(width 0.15)
				(type solid)
			)
			(fill no)
			(layer "F.Fab")
		)
		(pad "1" smd roundrect
			(at -0.7 0)
			(size 0.6 0.8)
			(layers "F.Cu" "F.Mask" "F.Paste")
			(roundrect_rratio 0.2)
			(net 35 "+1V8")
			(pintype "passive")
		)
		(pad "2" smd roundrect
			(at 0.7 0)
			(size 0.6 0.8)
			(layers "F.Cu" "F.Mask" "F.Paste")
			(roundrect_rratio 0.2)
			(net 7 "/Power supply/VOUT1")
			(pintype "passive")
		)
	)
	(footprint "antmicro-footprints:R_Array_4x0402_Panasonic_EXB28V"
		(layer "F.Cu")
		(at 119.35 93.8)
		(property "Reference" "R4"
			(at -1.301 -1.45 0)
			(unlocked yes)
			(layer "F.SilkS")
			(effects
				(font
					(size 0.7 0.7)
					(thickness 0.15)
				)
				(justify left bottom)
			)
		)
		(property "Value" "R_4x100R_0402_array"
			(at -1.5 2 0)
			(layer "F.Fab")
			(effects
				(font
					(size 0.7 0.7)
					(thickness 0.15)
				)
				(justify left bottom)
			)
		)
		(property "Author" "Antmicro"
			(at 0 0 0)
			(layer "F.Fab")
			(hide yes)
			(effects
				(font
					(size 1 1)
					(thickness 0.15)
				)
			)
		)
		(property "License" "Apache-2.0"
			(at 0 0 0)
			(layer "F.Fab")
			(hide yes)
			(effects
				(font
					(size 1 1)
					(thickness 0.15)
				)
			)
		)
		(property "MPN" "EXB-28V101JX"
			(at 0 0 0)
			(layer "F.Fab")
			(hide yes)
			(effects
				(font
					(size 1 1)
					(thickness 0.15)
				)
			)
		)
		(property "Manufacturer" "Panasonic"
			(at 0 0 0)
			(layer "F.Fab")
			(hide yes)
			(effects
				(font
					(size 1 1)
					(thickness 0.15)
				)
			)
		)
		(property "Val" "R_4x100R_0402"
			(at 0 0 0)
			(layer "F.Fab")
			(hide yes)
			(effects
				(font
					(size 1 1)
					(thickness 0.15)
				)
			)
		)
		(sheetname "Translators")
		(sheetfile "translators.kicad_sch")
		(attr smd)
		(fp_line
			(start -1.25 -0.5)
			(end -1.25 0.498)
			(stroke
				(width 0.15)
				(type solid)
			)
			(layer "F.SilkS")
		)
		(fp_line
			(start 1.25 0.499)
			(end 1.25 -0.499)
			(stroke
				(width 0.15)
				(type solid)
			)
			(layer "F.SilkS")
		)
		(fp_rect
			(start -1.25 -0.8)
			(end 1.25 0.8)
			(stroke
				(width 0.05)
				(type solid)
			)
			(fill no)
			(layer "F.CrtYd")
		)
		(fp_line
			(start -1 -0.5)
			(end 0.998 -0.5)
			(stroke
				(width 0.15)
				(type solid)
			)
			(layer "F.Fab")
		)
		(fp_line
			(start -1 0.498)
			(end -1 -0.5)
			(stroke
				(width 0.15)
				(type solid)
			)
			(layer "F.Fab")
		)
		(fp_line
			(start 0.998 -0.5)
			(end 0.998 0.498)
			(stroke
				(width 0.15)
				(type solid)
			)
			(layer "F.Fab")
		)
		(fp_line
			(start 0.998 0.498)
			(end -1 0.498)
			(stroke
				(width 0.15)
				(type solid)
			)
			(layer "F.Fab")
		)
		(pad "1" smd roundrect
			(at -0.8875 0.45)
			(size 0.525 0.5)
			(layers "F.Cu" "F.Mask" "F.Paste")
			(roundrect_rratio 0.25)
			(net 169 "/SODIMM/LPDDR5_IN_A.DQ3")
			(pinfunction "R1.1")
			(pintype "passive")
		)
		(pad "2" smd roundrect
			(at -0.25 0.45)
			(size 0.25 0.5)
			(layers "F.Cu" "F.Mask" "F.Paste")
			(roundrect_rratio 0.25)
			(net 168 "/SODIMM/LPDDR5_IN_A.DQ1")
			(pinfunction "R2.1")
			(pintype "passive")
		)
		(pad "3" smd roundrect
			(at 0.25 0.45)
			(size 0.25 0.5)
			(layers "F.Cu" "F.Mask" "F.Paste")
			(roundrect_rratio 0.25)
			(net 167 "/SODIMM/LPDDR5_IN_A.DQ2")
			(pinfunction "R3.1")
			(pintype "passive")
		)
		(pad "4" smd roundrect
			(at 0.8875 0.45)
			(size 0.525 0.5)
			(layers "F.Cu" "F.Mask" "F.Paste")
			(roundrect_rratio 0.25)
			(net 166 "/SODIMM/LPDDR5_IN_A.DQ0")
			(pinfunction "R4.1")
			(pintype "passive")
		)
		(pad "5" smd roundrect
			(at 0.8875 -0.45)
			(size 0.525 0.5)
			(layers "F.Cu" "F.Mask" "F.Paste")
			(roundrect_rratio 0.25)
			(net 205 "/LPDDR5/LPDDR5_A.DQ0")
			(pinfunction "R4.2")
			(pintype "passive")
		)
		(pad "6" smd roundrect
			(at 0.25 -0.45)
			(size 0.25 0.5)
			(layers "F.Cu" "F.Mask" "F.Paste")
			(roundrect_rratio 0.25)
			(net 203 "/LPDDR5/LPDDR5_A.DQ2")
			(pinfunction "R3.2")
			(pintype "passive")
		)
		(pad "7" smd roundrect
			(at -0.25 -0.45)
			(size 0.25 0.5)
			(layers "F.Cu" "F.Mask" "F.Paste")
			(roundrect_rratio 0.25)
			(net 204 "/LPDDR5/LPDDR5_A.DQ1")
			(pinfunction "R2.2")
			(pintype "passive")
		)
		(pad "8" smd roundrect
			(at -0.8875 -0.45)
			(size 0.525 0.5)
			(layers "F.Cu" "F.Mask" "F.Paste")
			(roundrect_rratio 0.25)
			(net 202 "/LPDDR5/LPDDR5_A.DQ3")
			(pinfunction "R1.2")
			(pintype "passive")
		)
	)
	(footprint "antmicro-footprints:R_0402_1005Metric"
		(layer "F.Cu")
		(at 110 73.75)
		(descr "Resistor SMD 0402")
		(tags "resistor SMD 0402")
		(property "Reference" "R38"
			(at 0.9 0.45 0)
			(unlocked yes)
			(layer "F.SilkS")
			(effects
				(font
					(size 0.7 0.7)
					(thickness 0.15)
				)
				(justify left bottom)
			)
		)
		(property "Value" "R_130k_0402"
			(at -1.011843 1.772047 0)
			(layer "F.Fab")
			(effects
				(font
					(size 0.7 0.7)
					(thickness 0.15)
				)
				(justify left bottom)
			)
		)
		(property "Author" "Antmicro"
			(at 0 0 0)
			(layer "F.Fab")
			(hide yes)
			(effects
				(font
					(size 1 1)
					(thickness 0.15)
				)
			)
		)
		(property "License" "Apache-2.0"
			(at 0 0 0)
			(layer "F.Fab")
			(hide yes)
			(effects
				(font
					(size 1 1)
					(thickness 0.15)
				)
			)
		)
		(property "MPN" "CR0402-FX-1303GLF"
			(at 0 0 0)
			(layer "F.Fab")
			(hide yes)
			(effects
				(font
					(size 1 1)
					(thickness 0.15)
				)
			)
		)
		(property "Manufacturer" "Bourns"
			(at 0 0 0)
			(layer "F.Fab")
			(hide yes)
			(effects
				(font
					(size 1 1)
					(thickness 0.15)
				)
			)
		)
		(property "Tolerance" "1%"
			(at 0 0 0)
			(layer "F.Fab")
			(hide yes)
			(effects
				(font
					(size 1 1)
					(thickness 0.15)
				)
			)
		)
		(property "Val" "130k"
			(at 0 0 0)
			(layer "F.Fab")
			(hide yes)
			(effects
				(font
					(size 1 1)
					(thickness 0.15)
				)
			)
		)
		(sheetname "Power supply")
		(sheetfile "power_supply.kicad_sch")
		(attr smd)
		(fp_rect
			(start -0.93 -0.47)
			(end 0.93 0.47)
			(stroke
				(width 0.05)
				(type solid)
			)
			(fill no)
			(layer "F.CrtYd")
		)
		(fp_rect
			(start -0.5 -0.25)
			(end 0.5 0.25)
			(stroke
				(width 0.15)
				(type solid)
			)
			(fill no)
			(layer "F.Fab")
		)
		(pad "1" smd roundrect
			(at -0.485 0)
			(size 0.59 0.64)
			(layers "F.Cu" "F.Mask" "F.Paste")
			(roundrect_rratio 0.25)
			(net 72 "/Power supply/FB3")
			(pintype "passive")
		)
		(pad "2" smd roundrect
			(at 0.485 0)
			(size 0.59 0.64)
			(layers "F.Cu" "F.Mask" "F.Paste")
			(roundrect_rratio 0.25)
			(net 14 "GND")
			(pintype "passive")
		)
	)
	(footprint "antmicro-footprints:C_0402_1005Metric"
		(layer "F.Cu")
		(at 133.675 72.275)
		(descr "Capacitor SMD 0402")
		(tags "capacitor SMD 0402")
		(property "Reference" "C62"
			(at -1.075 -0.75 0)
			(unlocked yes)
			(layer "F.SilkS")
			(effects
				(font
					(size 0.7 0.7)
					(thickness 0.15)
				)
				(justify left bottom)
			)
		)
		(property "Value" "C_4u7_0402"
			(at -1.022927 2.155213 0)
			(layer "F.Fab")
			(effects
				(font
					(size 0.7 0.7)
					(thickness 0.15)
				)
				(justify left bottom)
			)
		)
		(property "Author" "Antmicro"
			(at 0 0 0)
			(layer "F.Fab")
			(hide yes)
			(effects
				(font
					(size 1 1)
					(thickness 0.15)
				)
			)
		)
		(property "Dielectric" ""
			(at 0 0 0)
			(layer "F.Fab")
			(hide yes)
			(effects
				(font
					(size 1 1)
					(thickness 0.15)
				)
			)
		)
		(property "License" "Apache-2.0"
			(at 0 0 0)
			(layer "F.Fab")
			(hide yes)
			(effects
				(font
					(size 1 1)
					(thickness 0.15)
				)
			)
		)
		(property "MPN" "GRM155R61A475MEAAD"
			(at 0 0 0)
			(layer "F.Fab")
			(hide yes)
			(effects
				(font
					(size 1 1)
					(thickness 0.15)
				)
			)
		)
		(property "Manufacturer" "Murata"
			(at 0 0 0)
			(layer "F.Fab")
			(hide yes)
			(effects
				(font
					(size 1 1)
					(thickness 0.15)
				)
			)
		)
		(property "Val" "4u7"
			(at 0 0 0)
			(layer "F.Fab")
			(hide yes)
			(effects
				(font
					(size 1 1)
					(thickness 0.15)
				)
			)
		)
		(property "Voltage" ""
			(at 0 0 0)
			(layer "F.Fab")
			(hide yes)
			(effects
				(font
					(size 1 1)
					(thickness 0.15)
				)
			)
		)
		(sheetname "LPDDR5")
		(sheetfile "lpddr5.kicad_sch")
		(attr smd)
		(fp_rect
			(start -0.9659 -0.481258)
			(end 0.9649 0.458742)
			(stroke
				(width 0.05)
				(type solid)
			)
			(fill no)
			(layer "F.CrtYd")
		)
		(fp_line
			(start -0.499 -0.25)
			(end 0.499 -0.25)
			(stroke
				(width 0.15)
				(type solid)
			)
			(layer "F.Fab")
		)
		(fp_line
			(start -0.499 0.248)
			(end -0.499 -0.25)
			(stroke
				(width 0.15)
				(type solid)
			)
			(layer "F.Fab")
		)
		(fp_line
			(start 0.499 -0.25)
			(end 0.499 0.248)
			(stroke
				(width 0.15)
				(type solid)
			)
			(layer "F.Fab")
		)
		(fp_line
			(start 0.499 0.248)
			(end -0.499 0.248)
			(stroke
				(width 0.15)
				(type solid)
			)
			(layer "F.Fab")
		)
		(pad "1" smd roundrect
			(at -0.484 0)
			(size 0.59 0.64)
			(layers "F.Cu" "F.Mask" "F.Paste")
			(roundrect_rratio 0.25)
			(net 14 "GND")
			(pintype "passive")
		)
		(pad "2" smd roundrect
			(at 0.484 0)
			(size 0.59 0.64)
			(layers "F.Cu" "F.Mask" "F.Paste")
			(roundrect_rratio 0.25)
			(net 13 "+1V05")
			(pintype "passive")
		)
	)
	(footprint "antmicro-footprints:C_0402_1005Metric"
		(layer "F.Cu")
		(at 144.25 79 90)
		(descr "Capacitor SMD 0402")
		(tags "capacitor SMD 0402")
		(property "Reference" "C60"
			(at 1 0.325 90)
			(unlocked yes)
			(layer "F.SilkS")
			(effects
				(font
					(size 0.7 0.7)
					(thickness 0.15)
				)
				(justify left bottom)
			)
		)
		(property "Value" "C_4u7_0402"
			(at -1.022927 2.155213 90)
			(layer "F.Fab")
			(effects
				(font
					(size 0.7 0.7)
					(thickness 0.15)
				)
				(justify left bottom)
			)
		)
		(property "Author" "Antmicro"
			(at 223.25 -65.25 0)
			(layer "F.Fab")
			(hide yes)
			(effects
				(font
					(size 1 1)
					(thickness 0.15)
				)
			)
		)
		(property "Dielectric" ""
			(at 223.25 -65.25 0)
			(layer "F.Fab")
			(hide yes)
			(effects
				(font
					(size 1 1)
					(thickness 0.15)
				)
			)
		)
		(property "License" "Apache-2.0"
			(at 223.25 -65.25 0)
			(layer "F.Fab")
			(hide yes)
			(effects
				(font
					(size 1 1)
					(thickness 0.15)
				)
			)
		)
		(property "MPN" "GRM155R61A475MEAAD"
			(at 223.25 -65.25 0)
			(layer "F.Fab")
			(hide yes)
			(effects
				(font
					(size 1 1)
					(thickness 0.15)
				)
			)
		)
		(property "Manufacturer" "Murata"
			(at 223.25 -65.25 0)
			(layer "F.Fab")
			(hide yes)
			(effects
				(font
					(size 1 1)
					(thickness 0.15)
				)
			)
		)
		(property "Val" "4u7"
			(at 223.25 -65.25 0)
			(layer "F.Fab")
			(hide yes)
			(effects
				(font
					(size 1 1)
					(thickness 0.15)
				)
			)
		)
		(property "Voltage" ""
			(at 223.25 -65.25 0)
			(layer "F.Fab")
			(hide yes)
			(effects
				(font
					(size 1 1)
					(thickness 0.15)
				)
			)
		)
		(sheetname "LPDDR5")
		(sheetfile "lpddr5.kicad_sch")
		(attr smd)
		(fp_rect
			(start -0.9659 -0.481258)
			(end 0.9649 0.458742)
			(stroke
				(width 0.05)
				(type solid)
			)
			(fill no)
			(layer "F.CrtYd")
		)
		(fp_line
			(start 0.499 -0.25)
			(end 0.499 0.248)
			(stroke
				(width 0.15)
				(type solid)
			)
			(layer "F.Fab")
		)
		(fp_line
			(start -0.499 -0.25)
			(end 0.499 -0.25)
			(stroke
				(width 0.15)
				(type solid)
			)
			(layer "F.Fab")
		)
		(fp_line
			(start 0.499 0.248)
			(end -0.499 0.248)
			(stroke
				(width 0.15)
				(type solid)
			)
			(layer "F.Fab")
		)
		(fp_line
			(start -0.499 0.248)
			(end -0.499 -0.25)
			(stroke
				(width 0.15)
				(type solid)
			)
			(layer "F.Fab")
		)
		(pad "1" smd roundrect
			(at -0.484 0 90)
			(size 0.59 0.64)
			(layers "F.Cu" "F.Mask" "F.Paste")
			(roundrect_rratio 0.25)
			(net 14 "GND")
			(pintype "passive")
		)
		(pad "2" smd roundrect
			(at 0.484 0 90)
			(size 0.59 0.64)
			(layers "F.Cu" "F.Mask" "F.Paste")
			(roundrect_rratio 0.25)
			(net 12 "+0V9")
			(pintype "passive")
		)
	)
	(footprint "antmicro-footprints:R_0402_1005Metric"
		(layer "F.Cu")
		(at 136.15 91.35 90)
		(descr "Resistor SMD 0402")
		(tags "resistor SMD 0402")
		(property "Reference" "R15"
			(at -1.05 1.45 90)
			(unlocked yes)
			(layer "F.SilkS")
			(effects
				(font
					(size 0.7 0.7)
					(thickness 0.15)
				)
				(justify left bottom)
			)
		)
		(property "Value" "R_100R_0402"
			(at -1.011843 1.772047 90)
			(layer "F.Fab")
			(effects
				(font
					(size 0.7 0.7)
					(thickness 0.15)
				)
				(justify left bottom)
			)
		)
		(property "Author" "Antmicro"
			(at 227.5 -44.8 0)
			(layer "F.Fab")
			(hide yes)
			(effects
				(font
					(size 1 1)
					(thickness 0.15)
				)
			)
		)
		(property "License" "Apache-2.0"
			(at 227.5 -44.8 0)
			(layer "F.Fab")
			(hide yes)
			(effects
				(font
					(size 1 1)
					(thickness 0.15)
				)
			)
		)
		(property "MPN" "CR0402-FX-1000GLF"
			(at 227.5 -44.8 0)
			(layer "F.Fab")
			(hide yes)
			(effects
				(font
					(size 1 1)
					(thickness 0.15)
				)
			)
		)
		(property "Manufacturer" "Bourns"
			(at 227.5 -44.8 0)
			(layer "F.Fab")
			(hide yes)
			(effects
				(font
					(size 1 1)
					(thickness 0.15)
				)
			)
		)
		(property "Tolerance" "1%"
			(at 227.5 -44.8 0)
			(layer "F.Fab")
			(hide yes)
			(effects
				(font
					(size 1 1)
					(thickness 0.15)
				)
			)
		)
		(property "Val" "100R"
			(at 227.5 -44.8 0)
			(layer "F.Fab")
			(hide yes)
			(effects
				(font
					(size 1 1)
					(thickness 0.15)
				)
			)
		)
		(sheetname "Translators")
		(sheetfile "translators.kicad_sch")
		(attr smd)
		(fp_rect
			(start -0.93 -0.47)
			(end 0.93 0.47)
			(stroke
				(width 0.05)
				(type solid)
			)
			(fill no)
			(layer "F.CrtYd")
		)
		(fp_rect
			(start -0.5 -0.25)
			(end 0.5 0.25)
			(stroke
				(width 0.15)
				(type solid)
			)
			(fill no)
			(layer "F.Fab")
		)
		(pad "1" smd roundrect
			(at -0.485 0 90)
			(size 0.59 0.64)
			(layers "F.Cu" "F.Mask" "F.Paste")
			(roundrect_rratio 0.25)
			(net 155 "/SODIMM/LPDDR5_IN_A.CK_N")
			(pintype "passive")
		)
		(pad "2" smd roundrect
			(at 0.485 0 90)
			(size 0.59 0.64)
			(layers "F.Cu" "F.Mask" "F.Paste")
			(roundrect_rratio 0.25)
			(net 50 "/LPDDR5/LPDDR5_A.CK_N")
			(pintype "passive")
		)
	)
)
